(kicad_pcb
	(version 20241229)
	(generator "pcbnew")
	(generator_version "9.0")
	(general
		(thickness 1.6)
		(legacy_teardrops no)
	)
	(paper "A4")
	(title_block
		(title "GMSL Deserializer")
		(date "2025-10-09")
		(rev "1.0.4")
		(company "Antmicro Ltd")
		(comment 1 "www.antmicro.com")
		(comment 9 "footprints 26-31 of 235")
	)
	(layers
		(0 "F.Cu" signal)
		(4 "In1.Cu" power)
		(6 "In2.Cu" power)
		(2 "B.Cu" signal)
		(9 "F.Adhes" user "F.Adhesive")
		(11 "B.Adhes" user "B.Adhesive")
		(13 "F.Paste" user)
		(15 "B.Paste" user)
		(5 "F.SilkS" user "F.Silkscreen")
		(7 "B.SilkS" user "B.Silkscreen")
		(1 "F.Mask" user)
		(3 "B.Mask" user)
		(17 "Dwgs.User" user "User.Drawings")
		(19 "Cmts.User" user "User.Comments")
		(21 "Eco1.User" user "User.Eco1")
		(23 "Eco2.User" user "User.Eco2")
		(25 "Edge.Cuts" user)
		(27 "Margin" user)
		(31 "F.CrtYd" user "F.Courtyard")
		(29 "B.CrtYd" user "B.Courtyard")
		(35 "F.Fab" user)
		(33 "B.Fab" user)
	)
	(footprint "antmicro-footprints:SOD-523_NP"
		(layer "F.Cu")
		(at 181.864 62.3535 -90)
		(property "Reference" "D9"
			(at 8.5125 -0.254 90)
			(layer "F.SilkS")
			(effects
				(font
					(size 0.7 0.7)
					(thickness 0.15)
				)
				(justify right bottom)
			)
		)
		(property "Value" "ESD5B5_0ST1G"
			(at 0 1.499 90)
			(layer "F.Fab")
			(effects
				(font
					(size 0.7 0.7)
					(thickness 0.15)
				)
				(justify right bottom)
			)
		)
		(property "Datasheet" "https://www.onsemi.com/pdf/datasheet/esd5b5.0st1-d.pdf"
			(at 0 0 270)
			(layer "F.Fab")
			(hide yes)
			(effects
				(font
					(size 1.27 1.27)
					(thickness 0.15)
				)
			)
		)
		(property "Description" "Bidirectional TVS, 30 kV,  SOD-523, 5 V, 32 pF"
			(at 0 0 270)
			(layer "F.Fab")
			(hide yes)
			(effects
				(font
					(size 1.27 1.27)
					(thickness 0.15)
				)
			)
		)
		(property "Author" "Antmicro"
			(at 119.5105 244.2175 0)
			(layer "F.Fab")
			(hide yes)
			(effects
				(font
					(size 1 1)
					(thickness 0.15)
				)
			)
		)
		(property "License" "Apache-2.0"
			(at 119.5105 244.2175 0)
			(layer "F.Fab")
			(hide yes)
			(effects
				(font
					(size 1 1)
					(thickness 0.15)
				)
			)
		)
		(property "MPN" "ESD5B5.0ST1G"
			(at 119.5105 244.2175 0)
			(layer "F.Fab")
			(hide yes)
			(effects
				(font
					(size 1 1)
					(thickness 0.15)
				)
			)
		)
		(property "Manufacturer" "ON Semiconductor"
			(at 119.5105 244.2175 0)
			(layer "F.Fab")
			(hide yes)
			(effects
				(font
					(size 1 1)
					(thickness 0.15)
				)
			)
		)
		(sheetname "/Connectors/")
		(sheetfile "connectors.kicad_sch")
		(attr smd)
		(fp_rect
			(start -1 -0.6)
			(end 1 0.6)
			(stroke
				(width 0.05)
				(type solid)
			)
			(fill no)
			(layer "F.CrtYd")
		)
		(fp_line
			(start -0.652 0.423)
			(end 0.65 0.423)
			(stroke
				(width 0.15)
				(type solid)
			)
			(layer "F.Fab")
		)
		(fp_line
			(start -0.652 0.423)
			(end -0.652 -0.425)
			(stroke
				(width 0.15)
				(type solid)
			)
			(layer "F.Fab")
		)
		(fp_line
			(start -0.652 -0.425)
			(end 0.65 -0.425)
			(stroke
				(width 0.15)
				(type solid)
			)
			(layer "F.Fab")
		)
		(fp_line
			(start 0.65 -0.425)
			(end 0.65 0.423)
			(stroke
				(width 0.15)
				(type solid)
			)
			(layer "F.Fab")
		)
		(pad "1" smd roundrect
			(at -0.701 0 270)
			(size 0.5 0.6)
			(layers "F.Cu" "F.Mask" "F.Paste")
			(roundrect_rratio 0.25)
			(net 1 "GND")
			(pinfunction "C")
			(pintype "passive")
		)
		(pad "2" smd roundrect
			(at 0.699 0 270)
			(size 0.5 0.6)
			(layers "F.Cu" "F.Mask" "F.Paste")
			(roundrect_rratio 0.25)
			(net 50 "/Connectors/FFC_3V3")
			(pinfunction "A")
			(pintype "passive")
		)
	)
	(footprint "antmicro-footprints:C_0402_1005Metric"
		(layer "F.Cu")
		(at 127.436 85.702 -90)
		(descr "Capacitor SMD 0402")
		(tags "capacitor SMD 0402")
		(property "Reference" "C25"
			(at -0.485 -2.104 90)
			(layer "F.SilkS")
			(effects
				(font
					(size 0.7 0.7)
					(thickness 0.15)
				)
				(justify right bottom)
			)
		)
		(property "Value" "C_22u_0402"
			(at -1.022927 2.155213 90)
			(layer "F.Fab")
			(effects
				(font
					(size 0.7 0.7)
					(thickness 0.15)
				)
				(justify right bottom)
			)
		)
		(property "Datasheet" "https://www.murata.com/products/productdetail?partno=GRM158R60J226ME01%23"
			(at 0 0 270)
			(layer "F.Fab")
			(hide yes)
			(effects
				(font
					(size 1.27 1.27)
					(thickness 0.15)
				)
			)
		)
		(property "Description" "SMD Multilayer Ceramic Capacitor, 22 uF, 4 V, 0402 [1005 Metric], X6S"
			(at 0 0 270)
			(layer "F.Fab")
			(hide yes)
			(effects
				(font
					(size 1.27 1.27)
					(thickness 0.15)
				)
			)
		)
		(property "Author" "Antmicro"
			(at 41.734 213.138 0)
			(layer "F.Fab")
			(hide yes)
			(effects
				(font
					(size 1 1)
					(thickness 0.15)
				)
			)
		)
		(property "Dielectric" ""
			(at 41.734 213.138 0)
			(layer "F.Fab")
			(hide yes)
			(effects
				(font
					(size 1 1)
					(thickness 0.15)
				)
			)
		)
		(property "License" "Apache-2.0"
			(at 41.734 213.138 0)
			(layer "F.Fab")
			(hide yes)
			(effects
				(font
					(size 1 1)
					(thickness 0.15)
				)
			)
		)
		(property "MPN" "GRM158R60J226ME01D"
			(at 41.734 213.138 0)
			(layer "F.Fab")
			(hide yes)
			(effects
				(font
					(size 1 1)
					(thickness 0.15)
				)
			)
		)
		(property "Manufacturer" "Murata"
			(at 41.734 213.138 0)
			(layer "F.Fab")
			(hide yes)
			(effects
				(font
					(size 1 1)
					(thickness 0.15)
				)
			)
		)
		(property "Val" "22u"
			(at 41.734 213.138 0)
			(layer "F.Fab")
			(hide yes)
			(effects
				(font
					(size 1 1)
					(thickness 0.15)
				)
			)
		)
		(property "Voltage" ""
			(at 41.734 213.138 0)
			(layer "F.Fab")
			(hide yes)
			(effects
				(font
					(size 1 1)
					(thickness 0.15)
				)
			)
		)
		(sheetname "/Power/")
		(sheetfile "power.kicad_sch")
		(attr smd)
		(fp_rect
			(start -0.925 -0.47)
			(end 0.925 0.47)
			(stroke
				(width 0.05)
				(type default)
			)
			(fill no)
			(layer "F.CrtYd")
		)
		(fp_line
			(start -0.494 0.248)
			(end -0.494 -0.25)
			(stroke
				(width 0.15)
				(type solid)
			)
			(layer "F.Fab")
		)
		(fp_line
			(start 0.504 0.248)
			(end -0.494 0.248)
			(stroke
				(width 0.15)
				(type solid)
			)
			(layer "F.Fab")
		)
		(fp_line
			(start -0.494 -0.25)
			(end 0.504 -0.25)
			(stroke
				(width 0.15)
				(type solid)
			)
			(layer "F.Fab")
		)
		(fp_line
			(start 0.504 -0.25)
			(end 0.504 0.248)
			(stroke
				(width 0.15)
				(type solid)
			)
			(layer "F.Fab")
		)
		(pad "1" smd roundrect
			(at -0.48 0 270)
			(size 0.59 0.64)
			(layers "F.Cu" "F.Mask" "F.Paste")
			(roundrect_rratio 0.25)
			(net 1 "GND")
			(pintype "passive")
		)
		(pad "2" smd roundrect
			(at 0.48 0 270)
			(size 0.59 0.64)
			(layers "F.Cu" "F.Mask" "F.Paste")
			(roundrect_rratio 0.25)
			(net 11 "/Power/OUT_1V2")
			(pintype "passive")
		)
	)
	(footprint "antmicro-footprints:R_0603_1608Metric"
		(layer "F.Cu")
		(at 130.937 80.264 -90)
		(descr "Resistor SMD 0603")
		(tags "resistor SMD 0603")
		(property "Reference" "R62"
			(at -1.882 -1.596 90)
			(layer "F.SilkS")
			(effects
				(font
					(size 0.7 0.7)
					(thickness 0.15)
				)
				(justify right bottom)
			)
		)
		(property "Value" "R_0R_22.4A_0603"
			(at 0 1.6 90)
			(layer "F.Fab")
			(effects
				(font
					(size 0.7 0.7)
					(thickness 0.15)
				)
				(justify right bottom)
			)
		)
		(property "Datasheet" "https://fscdn.rohm.com/en/products/databook/datasheet/passive/resistor/chip_resistor/pmr-jpw-e.pdf"
			(at 0 0 270)
			(layer "F.Fab")
			(hide yes)
			(effects
				(font
					(size 1.27 1.27)
					(thickness 0.15)
				)
			)
		)
		(property "Description" "SMD Chip Resistor"
			(at 0 0 270)
			(layer "F.Fab")
			(hide yes)
			(effects
				(font
					(size 1.27 1.27)
					(thickness 0.15)
				)
			)
		)
		(property "Author" "Antmicro"
			(at 50.673 211.201 0)
			(layer "F.Fab")
			(hide yes)
			(effects
				(font
					(size 1 1)
					(thickness 0.15)
				)
			)
		)
		(property "License" "Apache-2.0"
			(at 50.673 211.201 0)
			(layer "F.Fab")
			(hide yes)
			(effects
				(font
					(size 1 1)
					(thickness 0.15)
				)
			)
		)
		(property "MPN" "PMR03EZPJ000"
			(at 50.673 211.201 0)
			(layer "F.Fab")
			(hide yes)
			(effects
				(font
					(size 1 1)
					(thickness 0.15)
				)
			)
		)
		(property "Manufacturer" "ROHM Semiconductor"
			(at 50.673 211.201 0)
			(layer "F.Fab")
			(hide yes)
			(effects
				(font
					(size 1 1)
					(thickness 0.15)
				)
			)
		)
		(property "Max. Curr." "22.4A"
			(at 50.673 211.201 0)
			(layer "F.Fab")
			(hide yes)
			(effects
				(font
					(size 1 1)
					(thickness 0.15)
				)
			)
		)
		(property "Tolerance" "template_tolerance"
			(at 50.673 211.201 0)
			(layer "F.Fab")
			(hide yes)
			(effects
				(font
					(size 1 1)
					(thickness 0.15)
				)
			)
		)
		(property "Val" "0R"
			(at 50.673 211.201 0)
			(layer "F.Fab")
			(hide yes)
			(effects
				(font
					(size 1 1)
					(thickness 0.15)
				)
			)
		)
		(sheetname "/Power/")
		(sheetfile "power.kicad_sch")
		(attr smd)
		(fp_line
			(start -0.15 0.4)
			(end 0.15 0.4)
			(stroke
				(width 0.15)
				(type solid)
			)
			(layer "F.SilkS")
		)
		(fp_line
			(start -0.15 -0.4)
			(end 0.15 -0.4)
			(stroke
				(width 0.15)
				(type solid)
			)
			(layer "F.SilkS")
		)
		(fp_rect
			(start -1.25 -0.65)
			(end 1.25 0.65)
			(stroke
				(width 0.05)
				(type solid)
			)
			(fill no)
			(layer "F.CrtYd")
		)
		(fp_rect
			(start -0.8 -0.4)
			(end 0.8 0.4)
			(stroke
				(width 0.15)
				(type solid)
			)
			(fill no)
			(layer "F.Fab")
		)
		(pad "1" smd roundrect
			(at -0.7 0 270)
			(size 0.8 1)
			(layers "F.Cu" "F.Mask" "F.Paste")
			(roundrect_rratio 0.2)
			(net 123 "/Power/OUT_12V")
			(pintype "passive")
		)
		(pad "2" smd roundrect
			(at 0.7 0 270)
			(size 0.8 1)
			(layers "F.Cu" "F.Mask" "F.Paste")
			(roundrect_rratio 0.2)
			(net 4 "+12V")
			(pintype "passive")
		)
	)
	(footprint "antmicro-footprints:LED_0603_1608Metric_G"
		(layer "F.Cu")
		(at 152.4 96.11 -90)
		(descr "LED SMD 0603 Green")
		(tags "LED SMD 0603 Green")
		(property "Reference" "D2"
			(at -1.782222 34.65 0)
			(layer "F.SilkS")
			(effects
				(font
					(size 0.7 0.7)
					(thickness 0.15)
				)
				(justify right bottom)
			)
		)
		(property "Value" "LED_G_0603_LTST-C190GKT"
			(at -0.001 1.599 90)
			(layer "F.Fab")
			(effects
				(font
					(size 0.7 0.7)
					(thickness 0.15)
				)
				(justify right bottom)
			)
		)
		(property "Datasheet" "https://media.digikey.com/pdf/Data%20Sheets/Lite-On%20PDFs/LTST-C190GKT.pdf"
			(at 0 0 270)
			(layer "F.Fab")
			(hide yes)
			(effects
				(font
					(size 1.27 1.27)
					(thickness 0.15)
				)
			)
		)
		(property "Description" "LED, Green, SMD, 0603, 20 mA, 2.1 V, 569 nm"
			(at 0 0 270)
			(layer "F.Fab")
			(hide yes)
			(effects
				(font
					(size 1.27 1.27)
					(thickness 0.15)
				)
			)
		)
		(property "Author" "Antmicro"
			(at 56.29 248.51 0)
			(layer "F.Fab")
			(hide yes)
			(effects
				(font
					(size 1 1)
					(thickness 0.15)
				)
			)
		)
		(property "Color" "Green"
			(at 56.29 248.51 0)
			(layer "F.Fab")
			(hide yes)
			(effects
				(font
					(size 1 1)
					(thickness 0.15)
				)
			)
		)
		(property "License" "Apache-2.0"
			(at 56.29 248.51 0)
			(layer "F.Fab")
			(hide yes)
			(effects
				(font
					(size 1 1)
					(thickness 0.15)
				)
			)
		)
		(property "MPN" "LTST-C190GKT"
			(at 56.29 248.51 0)
			(layer "F.Fab")
			(hide yes)
			(effects
				(font
					(size 1 1)
					(thickness 0.15)
				)
			)
		)
		(property "Manufacturer" "Lite-On"
			(at 56.29 248.51 0)
			(layer "F.Fab")
			(hide yes)
			(effects
				(font
					(size 1 1)
					(thickness 0.15)
				)
			)
		)
		(property "VSD_class" "LED"
			(at 56.29 248.51 0)
			(layer "F.Fab")
			(hide yes)
			(effects
				(font
					(size 1 1)
					(thickness 0.15)
				)
			)
		)
		(sheetname "/Connectors/")
		(sheetfile "connectors.kicad_sch")
		(attr smd)
		(fp_line
			(start 0.22 0.35)
			(end -0.22 0.35)
			(stroke
				(width 0.15)
				(type solid)
			)
			(layer "F.SilkS")
		)
		(fp_line
			(start -0.094672 0.201008)
			(end -0.094672 -0.198992)
			(stroke
				(width 0.1)
				(type solid)
			)
			(layer "F.SilkS")
		)
		(fp_line
			(start 0.105328 0.201008)
			(end -0.094672 0.001008)
			(stroke
				(width 0.1)
				(type solid)
			)
			(layer "F.SilkS")
		)
		(fp_line
			(start 0.105328 0.201008)
			(end 0.105328 -0.198992)
			(stroke
				(width 0.1)
				(type solid)
			)
			(layer "F.SilkS")
		)
		(fp_line
			(start -0.094672 0.001008)
			(end -0.24 0.001008)
			(stroke
				(width 0.1)
				(type solid)
			)
			(layer "F.SilkS")
		)
		(fp_line
			(start -0.094672 0.001008)
			(end 0.105328 -0.198992)
			(stroke
				(width 0.1)
				(type solid)
			)
			(layer "F.SilkS")
		)
		(fp_line
			(start 0.105328 0.001008)
			(end 0.24 0.001)
			(stroke
				(width 0.1)
				(type solid)
			)
			(layer "F.SilkS")
		)
		(fp_line
			(start -1.18 -0.319)
			(end -1.18 0.321)
			(stroke
				(width 0.15)
				(type solid)
			)
			(layer "F.SilkS")
		)
		(fp_line
			(start 0.22 -0.35)
			(end -0.22 -0.35)
			(stroke
				(width 0.15)
				(type solid)
			)
			(layer "F.SilkS")
		)
		(fp_rect
			(start 1.25 0.65)
			(end -1.25 -0.65)
			(stroke
				(width 0.05)
				(type solid)
			)
			(fill no)
			(layer "F.CrtYd")
		)
		(fp_line
			(start -0.199 0.2)
			(end -0.199 0.1)
			(stroke
				(width 0.15)
				(type solid)
			)
			(layer "F.Fab")
		)
		(fp_line
			(start 0.201 0.2)
			(end 0.201 0)
			(stroke
				(width 0.15)
				(type solid)
			)
			(layer "F.Fab")
		)
		(fp_line
			(start -0.199 0)
			(end -0.597 0)
			(stroke
				(width 0.15)
				(type solid)
			)
			(layer "F.Fab")
		)
		(fp_line
			(start -0.101 0)
			(end 0.201 0.2)
			(stroke
				(width 0.15)
				(type solid)
			)
			(layer "F.Fab")
		)
		(fp_line
			(start 0.201 0)
			(end 0.201 -0.202)
			(stroke
				(width 0.15)
				(type solid)
			)
			(layer "F.Fab")
		)
		(fp_line
			(start 0.599 0)
			(end 0.201 0)
			(stroke
				(width 0.15)
				(type solid)
			)
			(layer "F.Fab")
		)
		(fp_line
			(start -0.199 -0.202)
			(end -0.199 0.1)
			(stroke
				(width 0.15)
				(type solid)
			)
			(layer "F.Fab")
		)
		(fp_line
			(start 0.201 -0.202)
			(end -0.101 0)
			(stroke
				(width 0.15)
				(type solid)
			)
			(layer "F.Fab")
		)
		(fp_rect
			(start 0.848 0.4)
			(end -0.85 -0.402)
			(stroke
				(width 0.15)
				(type solid)
			)
			(fill no)
			(layer "F.Fab")
		)
		(pad "1" smd roundrect
			(at -0.7 0 90)
			(size 0.8 1)
			(layers "F.Cu" "F.Mask" "F.Paste")
			(roundrect_rratio 0.2)
			(net 64 "Net-(D2-C)")
			(pinfunction "C")
			(pintype "passive")
		)
		(pad "2" smd roundrect
			(at 0.7 0 90)
			(size 0.8 1)
			(layers "F.Cu" "F.Mask" "F.Paste")
			(roundrect_rratio 0.2)
			(net 2 "/Connectors/DC_UNFUSED")
			(pinfunction "A")
			(pintype "passive")
		)
	)
	(footprint "antmicro-footprints:R_0402_1005Metric"
		(layer "F.Cu")
		(at 131.064 76.962)
		(descr "Resistor SMD 0402")
		(tags "resistor SMD 0402")
		(property "Reference" "R30"
			(at 0.938 0.277 0)
			(layer "F.SilkS")
			(effects
				(font
					(size 0.7 0.7)
					(thickness 0.15)
				)
				(justify left bottom)
			)
		)
		(property "Value" "R_120k_0402"
			(at -1.011843 1.772047 0)
			(layer "F.Fab")
			(effects
				(font
					(size 0.7 0.7)
					(thickness 0.15)
				)
				(justify left bottom)
			)
		)
		(property "Datasheet" "https://www.bourns.com/docs/product-datasheets/cr.pdf"
			(at 0 0 0)
			(layer "F.Fab")
			(hide yes)
			(effects
				(font
					(size 1.27 1.27)
					(thickness 0.15)
				)
			)
		)
		(property "Description" "SMD Chip Resistor, 120 kohm, ± 1%, 100 mW, 0402 [1005 Metric], Thick Film, Precision"
			(at 0 0 0)
			(layer "F.Fab")
			(hide yes)
			(effects
				(font
					(size 1.27 1.27)
					(thickness 0.15)
				)
			)
		)
		(property "Author" "Antmicro"
			(at 0 0 0)
			(layer "F.Fab")
			(hide yes)
			(effects
				(font
					(size 1 1)
					(thickness 0.15)
				)
			)
		)
		(property "License" "Apache-2.0"
			(at 0 0 0)
			(layer "F.Fab")
			(hide yes)
			(effects
				(font
					(size 1 1)
					(thickness 0.15)
				)
			)
		)
		(property "MPN" "CR0402-FX-1203GLF"
			(at 0 0 0)
			(layer "F.Fab")
			(hide yes)
			(effects
				(font
					(size 1 1)
					(thickness 0.15)
				)
			)
		)
		(property "Manufacturer" "Bourns"
			(at 0 0 0)
			(layer "F.Fab")
			(hide yes)
			(effects
				(font
					(size 1 1)
					(thickness 0.15)
				)
			)
		)
		(property "Tolerance" "1%"
			(at 0 0 0)
			(layer "F.Fab")
			(hide yes)
			(effects
				(font
					(size 1 1)
					(thickness 0.15)
				)
			)
		)
		(property "Val" "120k"
			(at 0 0 0)
			(layer "F.Fab")
			(hide yes)
			(effects
				(font
					(size 1 1)
					(thickness 0.15)
				)
			)
		)
		(sheetname "/Power/")
		(sheetfile "power.kicad_sch")
		(attr smd)
		(fp_rect
			(start -0.925 -0.47)
			(end 0.925 0.47)
			(stroke
				(width 0.05)
				(type default)
			)
			(fill no)
			(layer "F.CrtYd")
		)
		(fp_rect
			(start -0.5 -0.25)
			(end 0.5 0.25)
			(stroke
				(width 0.15)
				(type solid)
			)
			(fill no)
			(layer "F.Fab")
		)
		(pad "1" smd roundrect
			(at -0.48 0)
			(size 0.59 0.64)
			(layers "F.Cu" "F.Mask" "F.Paste")
			(roundrect_rratio 0.25)
			(net 122 "/Power/FB_12V")
			(pintype "passive")
		)
		(pad "2" smd roundrect
			(at 0.48 0)
			(size 0.59 0.64)
			(layers "F.Cu" "F.Mask" "F.Paste")
			(roundrect_rratio 0.25)
			(net 123 "/Power/OUT_12V")
			(pintype "passive")
		)
	)
	(footprint "antmicro-footprints:R_0402_1005Metric"
		(layer "F.Cu")
		(at 153.1112 79.5528 -135)
		(descr "Resistor SMD 0402")
		(tags "resistor SMD 0402")
		(property "Reference" "R49"
			(at -1.185394 -2.298946 45)
			(layer "F.SilkS")
			(effects
				(font
					(size 0.7 0.7)
					(thickness 0.15)
				)
				(justify right bottom)
			)
		)
		(property "Value" "R_10k_0402"
			(at -1.011843 1.772046 45)
			(layer "F.Fab")
			(effects
				(font
					(size 0.7 0.7)
					(thickness 0.15)
				)
				(justify right bottom)
			)
		)
		(property "Datasheet" "https://www.bourns.com/docs/product-datasheets/cr.pdf"
			(at 0 0 225)
			(layer "F.Fab")
			(hide yes)
			(effects
				(font
					(size 1.27 1.27)
					(thickness 0.15)
				)
			)
		)
		(property "Description" "SMD Chip Resistor, 10 kohm, ± 1%, 62.5 mW, 0402 [1005 Metric], Thick Film, General Purpose"
			(at 0 0 225)
			(layer "F.Fab")
			(hide yes)
			(effects
				(font
					(size 1.27 1.27)
					(thickness 0.15)
				)
			)
		)
		(property "Author" "Antmicro"
			(at 205.124843 244.071092 0)
			(layer "F.Fab")
			(hide yes)
			(effects
				(font
					(size 1 1)
					(thickness 0.15)
				)
			)
		)
		(property "License" "Apache-2.0"
			(at 205.124843 244.071092 0)
			(layer "F.Fab")
			(hide yes)
			(effects
				(font
					(size 1 1)
					(thickness 0.15)
				)
			)
		)
		(property "MPN" "CR0402-FX-1002GLF"
			(at 205.124843 244.071092 0)
			(layer "F.Fab")
			(hide yes)
			(effects
				(font
					(size 1 1)
					(thickness 0.15)
				)
			)
		)
		(property "Manufacturer" "Bourns"
			(at 205.124843 244.071092 0)
			(layer "F.Fab")
			(hide yes)
			(effects
				(font
					(size 1 1)
					(thickness 0.15)
				)
			)
		)
		(property "Tolerance" "1%"
			(at 205.124843 244.071092 0)
			(layer "F.Fab")
			(hide yes)
			(effects
				(font
					(size 1 1)
					(thickness 0.15)
				)
			)
		)
		(property "Val" "10k"
			(at 205.124843 244.071092 0)
			(layer "F.Fab")
			(hide yes)
			(effects
				(font
					(size 1 1)
					(thickness 0.15)
				)
			)
		)
		(sheetname "/Deserializer/")
		(sheetfile "deserializer.kicad_sch")
		(attr smd)
		(fp_poly
			(pts
				(xy -0.925 -0.47) (xy 0.925 -0.47) (xy 0.925 0.47) (xy -0.925 0.47)
			)
			(stroke
				(width 0.05)
				(type default)
			)
			(fill no)
			(layer "F.CrtYd")
		)
		(fp_poly
			(pts
				(xy -0.5 -0.25) (xy 0.5 -0.25) (xy 0.5 0.25) (xy -0.5 0.25)
			)
			(stroke
				(width 0.15)
				(type solid)
			)
			(fill no)
			(layer "F.Fab")
		)
		(pad "1" smd roundrect
			(at -0.48 0 225)
			(size 0.59 0.64)
			(layers "F.Cu" "F.Mask" "F.Paste")
			(roundrect_rratio 0.25)
			(net 1 "GND")
			(pintype "passive")
		)
		(pad "2" smd roundrect
			(at 0.48 0 225)
			(size 0.59 0.64)
			(layers "F.Cu" "F.Mask" "F.Paste")
			(roundrect_rratio 0.25)
			(net 76 "/Deserializer/CFG0")
			(pintype "passive")
		)
	)
)
